(kicad_pcb
	(version 20260206)
	(generator "pcbnew")
	(generator_version "10.0")
	(general
		(thickness 1.6)
		(legacy_teardrops no)
	)
	(paper "A4")
	(title_block
		(title "04192023_DAF0TMB3IC0_F0TG_MB_C_brd_V02_OCP.brd")
		(comment 1 "Grand Teton / footprints 3847-3852 of 8354")
	)
	(layers
		(0 "F.Cu" signal "TOP")
		(4 "In1.Cu" signal "GND")
		(6 "In2.Cu" signal "IN1")
		(8 "In3.Cu" signal "GND1")
		(10 "In4.Cu" signal "IN2")
		(12 "In5.Cu" signal "GND2")
		(14 "In6.Cu" signal "IN3")
		(16 "In7.Cu" signal "GND3")
		(18 "In8.Cu" signal "VCC")
		(20 "In9.Cu" signal "VCC1")
		(22 "In10.Cu" signal "GND4")
		(24 "In11.Cu" signal "IN4")
		(26 "In12.Cu" signal "GND5")
		(28 "In13.Cu" signal "IN5")
		(30 "In14.Cu" signal "GND6")
		(32 "In15.Cu" signal "IN6")
		(34 "In16.Cu" signal "GND7")
		(2 "B.Cu" signal "BOTTOM")
		(9 "F.Adhes" user "F.Adhesive")
		(11 "B.Adhes" user "B.Adhesive")
		(13 "F.Paste" user "Package Geometry/Pastemask Top")
		(15 "B.Paste" user "Package Geometry/Pastemask Bottom")
		(5 "F.SilkS" user "Ref Des/Silkscreen Top")
		(7 "B.SilkS" user "Ref Des/Silkscreen Bottom")
		(1 "F.Mask" user "Board Geometry/Soldermask Top")
		(3 "B.Mask" user "Board Geometry/Soldermask Bottom")
		(17 "Dwgs.User" user "User.Drawings")
		(19 "Cmts.User" user "User.Comments")
		(21 "Eco1.User" user "User.Eco1")
		(23 "Eco2.User" user "User.Eco2")
		(25 "Edge.Cuts" user "Board Geometry/Outline")
		(27 "Margin" user)
		(31 "F.CrtYd" user "Package Geometry/Place Bound Top")
		(29 "B.CrtYd" user "Package Geometry/Place Bound Bottom")
		(35 "F.Fab" user "Ref Des/Assembly Top")
		(33 "B.Fab" user "Ref Des/Assembly Bottom")
	)
	(footprint ""
		(layer "F.Cu")
		(at 423.627296 -361.818682)
		(property "Reference" "PC198"
			(at 0 0 0)
			(layer "F.SilkS")
			(hide yes)
			(effects
				(font
					(size 1.27 1.27)
				)
			)
		)
		(property "Value" ""
			(at 0 0 0)
			(layer "F.Fab")
			(effects
				(font
					(size 1.27 1.27)
				)
			)
		)
		(duplicate_pad_numbers_are_jumpers no)
		(fp_line
			(start -0.7874 -0.4064)
			(end 0.7874 -0.4064)
			(stroke
				(width 0.1524)
				(type default)
			)
			(layer "F.SilkS")
		)
		(fp_line
			(start -0.7874 0.4064)
			(end -0.7874 -0.4064)
			(stroke
				(width 0.1524)
				(type default)
			)
			(layer "F.SilkS")
		)
		(fp_line
			(start 0.7874 -0.4064)
			(end 0.7874 0.4064)
			(stroke
				(width 0.1524)
				(type default)
			)
			(layer "F.SilkS")
		)
		(fp_line
			(start 0.7874 0.4064)
			(end -0.7874 0.4064)
			(stroke
				(width 0.1524)
				(type default)
			)
			(layer "F.SilkS")
		)
		(fp_line
			(start -0.67945 -0.305054)
			(end -0.12065 -0.305054)
			(stroke
				(width 0.1)
				(type default)
			)
			(layer "F.Fab")
		)
		(fp_line
			(start -0.67945 0.3048)
			(end -0.67945 -0.305054)
			(stroke
				(width 0.1)
				(type default)
			)
			(layer "F.Fab")
		)
		(fp_line
			(start -0.12065 -0.305054)
			(end -0.12065 -0.2794)
			(stroke
				(width 0.1)
				(type default)
			)
			(layer "F.Fab")
		)
		(fp_line
			(start -0.12065 -0.2794)
			(end 0.12065 -0.2794)
			(stroke
				(width 0.1)
				(type default)
			)
			(layer "F.Fab")
		)
		(fp_line
			(start -0.12065 0.2794)
			(end -0.12065 0.3048)
			(stroke
				(width 0.1)
				(type default)
			)
			(layer "F.Fab")
		)
		(fp_line
			(start -0.12065 0.3048)
			(end -0.67945 0.3048)
			(stroke
				(width 0.1)
				(type default)
			)
			(layer "F.Fab")
		)
		(fp_line
			(start 0.120396 0.2794)
			(end -0.12065 0.2794)
			(stroke
				(width 0.1)
				(type default)
			)
			(layer "F.Fab")
		)
		(fp_line
			(start 0.120396 0.3048)
			(end 0.120396 0.2794)
			(stroke
				(width 0.1)
				(type default)
			)
			(layer "F.Fab")
		)
		(fp_line
			(start 0.12065 -0.3048)
			(end 0.67945 -0.3048)
			(stroke
				(width 0.1)
				(type default)
			)
			(layer "F.Fab")
		)
		(fp_line
			(start 0.12065 -0.2794)
			(end 0.12065 -0.3048)
			(stroke
				(width 0.1)
				(type default)
			)
			(layer "F.Fab")
		)
		(fp_line
			(start 0.67945 -0.3048)
			(end 0.67945 0.3048)
			(stroke
				(width 0.1)
				(type default)
			)
			(layer "F.Fab")
		)
		(fp_line
			(start 0.67945 0.3048)
			(end 0.120396 0.3048)
			(stroke
				(width 0.1)
				(type default)
			)
			(layer "F.Fab")
		)
		(pad "1" smd circle
			(at -0.40005 0)
			(size 0 0)
			(layers "F.Cu" "F.Mask" "F.Paste")
			(net "PVDD11_S3_P0_TEMP0")
		)
		(pad "2" smd circle
			(at 0.40005 0)
			(size 0 0)
			(layers "F.Cu" "F.Mask" "F.Paste")
			(net "GND")
		)
	)
	(footprint ""
		(layer "F.Cu")
		(at 351.783904 -330.617322)
		(property "Reference" "PL7"
			(at -1.591056 -16.141446 0)
			(unlocked yes)
			(layer "F.SilkS")
			(effects
				(font
					(size 0.7874 0.5842)
					(thickness 0.1524)
				)
				(justify left)
			)
		)
		(property "Value" ""
			(at 0 0 0)
			(layer "F.Fab")
			(effects
				(font
					(size 1.27 1.27)
				)
			)
		)
		(duplicate_pad_numbers_are_jumpers no)
		(fp_line
			(start -3.750056 -5.500116)
			(end -2.393442 -5.500116)
			(stroke
				(width 0.1524)
				(type default)
			)
			(layer "F.SilkS")
		)
		(fp_line
			(start -3.750056 5.500116)
			(end -3.750056 -5.500116)
			(stroke
				(width 0.1524)
				(type default)
			)
			(layer "F.SilkS")
		)
		(fp_line
			(start -2.393442 5.500116)
			(end -3.750056 5.500116)
			(stroke
				(width 0.1524)
				(type default)
			)
			(layer "F.SilkS")
		)
		(fp_line
			(start 2.393442 5.500116)
			(end 3.750056 5.500116)
			(stroke
				(width 0.1524)
				(type default)
			)
			(layer "F.SilkS")
		)
		(fp_line
			(start 3.750056 -5.500116)
			(end 2.393442 -5.500116)
			(stroke
				(width 0.1524)
				(type default)
			)
			(layer "F.SilkS")
		)
		(fp_line
			(start 3.750056 5.500116)
			(end 3.750056 -5.500116)
			(stroke
				(width 0.1524)
				(type default)
			)
			(layer "F.SilkS")
		)
		(fp_poly
			(pts
				(xy -3.924808 -3.63601) (xy -4.283964 -2.558288) (xy -5.00253 -3.276854)
			)
			(stroke
				(width 0)
				(type default)
			)
			(fill yes)
			(layer "F.SilkS")
		)
		(fp_line
			(start -3.750056 -5.500116)
			(end -3.750056 5.500116)
			(stroke
				(width 0.1)
				(type default)
			)
			(layer "F.Fab")
		)
		(fp_line
			(start -3.750056 5.500116)
			(end 3.750056 5.500116)
			(stroke
				(width 0.1)
				(type default)
			)
			(layer "F.Fab")
		)
		(fp_line
			(start 3.750056 -5.500116)
			(end -3.750056 -5.500116)
			(stroke
				(width 0.1)
				(type default)
			)
			(layer "F.Fab")
		)
		(fp_line
			(start 3.750056 5.500116)
			(end 3.750056 -5.500116)
			(stroke
				(width 0.1)
				(type default)
			)
			(layer "F.Fab")
		)
		(fp_poly
			(pts
				(xy -4.9276 -4.757928) (xy -4.9276 -3.741928) (xy -3.9116 -4.249928)
			)
			(stroke
				(width 0)
				(type default)
			)
			(fill yes)
			(layer "F.Fab")
		)
		(pad "1" smd rect
			(at 0 -4.249928 270)
			(size 2.413 4.5212)
			(layers "F.Cu" "F.Mask" "F.Paste")
			(net "SW_PVDDCR_CPU1_P0_SW6")
		)
		(pad "2" smd rect
			(at 0 -1.175004 270)
			(size 1.3716 4.5212)
			(layers "F.Cu" "F.Mask" "F.Paste")
			(net "IND_CPU1_P0_CPL0")
		)
		(pad "3" smd rect
			(at 0 1.175004 270)
			(size 1.3716 4.5212)
			(layers "F.Cu" "F.Mask" "F.Paste")
			(net "IND_CPU1_P0_CPL6")
		)
		(pad "4" smd rect
			(at 0 4.249928 270)
			(size 2.413 4.5212)
			(layers "F.Cu" "F.Mask" "F.Paste")
			(net "PVDDCR_CPU1_P0")
		)
	)
	(footprint ""
		(layer "F.Cu")
		(at 221.67088 -44.922948 180)
		(property "Reference" "R3532"
			(at 0 0 180)
			(layer "F.SilkS")
			(hide yes)
			(effects
				(font
					(size 1.27 1.27)
				)
			)
		)
		(property "Value" ""
			(at 0 0 180)
			(layer "F.Fab")
			(effects
				(font
					(size 1.27 1.27)
				)
			)
		)
		(duplicate_pad_numbers_are_jumpers no)
		(fp_line
			(start 0.7874 0.4064)
			(end -0.7874 0.4064)
			(stroke
				(width 0.1524)
				(type default)
			)
			(layer "F.SilkS")
		)
		(fp_line
			(start 0.7874 -0.4064)
			(end 0.7874 0.4064)
			(stroke
				(width 0.1524)
				(type default)
			)
			(layer "F.SilkS")
		)
		(fp_line
			(start -0.7874 0.4064)
			(end -0.7874 -0.4064)
			(stroke
				(width 0.1524)
				(type default)
			)
			(layer "F.SilkS")
		)
		(fp_line
			(start -0.7874 -0.4064)
			(end 0.7874 -0.4064)
			(stroke
				(width 0.1524)
				(type default)
			)
			(layer "F.SilkS")
		)
		(fp_line
			(start 0.67945 0.3048)
			(end 0.120396 0.3048)
			(stroke
				(width 0.1)
				(type default)
			)
			(layer "F.Fab")
		)
		(fp_line
			(start 0.67945 -0.3048)
			(end 0.67945 0.3048)
			(stroke
				(width 0.1)
				(type default)
			)
			(layer "F.Fab")
		)
		(fp_line
			(start 0.12065 -0.2794)
			(end 0.12065 -0.3048)
			(stroke
				(width 0.1)
				(type default)
			)
			(layer "F.Fab")
		)
		(fp_line
			(start 0.12065 -0.3048)
			(end 0.67945 -0.3048)
			(stroke
				(width 0.1)
				(type default)
			)
			(layer "F.Fab")
		)
		(fp_line
			(start 0.120396 0.3048)
			(end 0.120396 0.2794)
			(stroke
				(width 0.1)
				(type default)
			)
			(layer "F.Fab")
		)
		(fp_line
			(start 0.120396 0.2794)
			(end -0.12065 0.2794)
			(stroke
				(width 0.1)
				(type default)
			)
			(layer "F.Fab")
		)
		(fp_line
			(start -0.12065 0.3048)
			(end -0.67945 0.3048)
			(stroke
				(width 0.1)
				(type default)
			)
			(layer "F.Fab")
		)
		(fp_line
			(start -0.12065 0.2794)
			(end -0.12065 0.3048)
			(stroke
				(width 0.1)
				(type default)
			)
			(layer "F.Fab")
		)
		(fp_line
			(start -0.12065 -0.2794)
			(end 0.12065 -0.2794)
			(stroke
				(width 0.1)
				(type default)
			)
			(layer "F.Fab")
		)
		(fp_line
			(start -0.12065 -0.305054)
			(end -0.12065 -0.2794)
			(stroke
				(width 0.1)
				(type default)
			)
			(layer "F.Fab")
		)
		(fp_line
			(start -0.67945 0.3048)
			(end -0.67945 -0.305054)
			(stroke
				(width 0.1)
				(type default)
			)
			(layer "F.Fab")
		)
		(fp_line
			(start -0.67945 -0.305054)
			(end -0.12065 -0.305054)
			(stroke
				(width 0.1)
				(type default)
			)
			(layer "F.Fab")
		)
		(pad "1" smd circle
			(at -0.40005 0 180)
			(size 0 0)
			(layers "F.Cu" "F.Mask" "F.Paste")
			(net "P3V3_E1S_0")
		)
		(pad "2" smd circle
			(at 0.40005 0 180)
			(size 0 0)
			(layers "F.Cu" "F.Mask" "F.Paste")
			(net "SMB_E1S_3V3AUX_ISO_SDA_R")
		)
	)
	(footprint ""
		(layer "F.Cu")
		(at 315.771022 -31.429706 180)
		(property "Reference" "C2044"
			(at 0 0 180)
			(layer "F.SilkS")
			(hide yes)
			(effects
				(font
					(size 1.27 1.27)
				)
			)
		)
		(property "Value" ""
			(at 0 0 180)
			(layer "F.Fab")
			(effects
				(font
					(size 1.27 1.27)
				)
			)
		)
		(duplicate_pad_numbers_are_jumpers no)
		(fp_line
			(start 0.7874 0.4064)
			(end -0.7874 0.4064)
			(stroke
				(width 0.1524)
				(type default)
			)
			(layer "F.SilkS")
		)
		(fp_line
			(start 0.7874 -0.4064)
			(end 0.7874 0.4064)
			(stroke
				(width 0.1524)
				(type default)
			)
			(layer "F.SilkS")
		)
		(fp_line
			(start -0.7874 0.4064)
			(end -0.7874 -0.4064)
			(stroke
				(width 0.1524)
				(type default)
			)
			(layer "F.SilkS")
		)
		(fp_line
			(start -0.7874 -0.4064)
			(end 0.7874 -0.4064)
			(stroke
				(width 0.1524)
				(type default)
			)
			(layer "F.SilkS")
		)
		(fp_line
			(start 0.67945 0.3048)
			(end 0.120396 0.3048)
			(stroke
				(width 0.1)
				(type default)
			)
			(layer "F.Fab")
		)
		(fp_line
			(start 0.67945 -0.3048)
			(end 0.67945 0.3048)
			(stroke
				(width 0.1)
				(type default)
			)
			(layer "F.Fab")
		)
		(fp_line
			(start 0.12065 -0.2794)
			(end 0.12065 -0.3048)
			(stroke
				(width 0.1)
				(type default)
			)
			(layer "F.Fab")
		)
		(fp_line
			(start 0.12065 -0.3048)
			(end 0.67945 -0.3048)
			(stroke
				(width 0.1)
				(type default)
			)
			(layer "F.Fab")
		)
		(fp_line
			(start 0.120396 0.3048)
			(end 0.120396 0.2794)
			(stroke
				(width 0.1)
				(type default)
			)
			(layer "F.Fab")
		)
		(fp_line
			(start 0.120396 0.2794)
			(end -0.12065 0.2794)
			(stroke
				(width 0.1)
				(type default)
			)
			(layer "F.Fab")
		)
		(fp_line
			(start -0.12065 0.3048)
			(end -0.67945 0.3048)
			(stroke
				(width 0.1)
				(type default)
			)
			(layer "F.Fab")
		)
		(fp_line
			(start -0.12065 0.2794)
			(end -0.12065 0.3048)
			(stroke
				(width 0.1)
				(type default)
			)
			(layer "F.Fab")
		)
		(fp_line
			(start -0.12065 -0.2794)
			(end 0.12065 -0.2794)
			(stroke
				(width 0.1)
				(type default)
			)
			(layer "F.Fab")
		)
		(fp_line
			(start -0.12065 -0.305054)
			(end -0.12065 -0.2794)
			(stroke
				(width 0.1)
				(type default)
			)
			(layer "F.Fab")
		)
		(fp_line
			(start -0.67945 0.3048)
			(end -0.67945 -0.305054)
			(stroke
				(width 0.1)
				(type default)
			)
			(layer "F.Fab")
		)
		(fp_line
			(start -0.67945 -0.305054)
			(end -0.12065 -0.305054)
			(stroke
				(width 0.1)
				(type default)
			)
			(layer "F.Fab")
		)
		(pad "1" smd circle
			(at -0.40005 0 180)
			(size 0 0)
			(layers "F.Cu" "F.Mask" "F.Paste")
			(net "P5V_ADC_MAM")
		)
		(pad "2" smd circle
			(at 0.40005 0 180)
			(size 0 0)
			(layers "F.Cu" "F.Mask" "F.Paste")
			(net "GND")
		)
	)
	(footprint ""
		(layer "F.Cu")
		(at 323.637148 -43.573954)
		(property "Reference" "R3685"
			(at 0 0 0)
			(layer "F.SilkS")
			(hide yes)
			(effects
				(font
					(size 1.27 1.27)
				)
			)
		)
		(property "Value" ""
			(at 0 0 0)
			(layer "F.Fab")
			(effects
				(font
					(size 1.27 1.27)
				)
			)
		)
		(duplicate_pad_numbers_are_jumpers no)
		(fp_line
			(start -0.7874 -0.4064)
			(end 0.7874 -0.4064)
			(stroke
				(width 0.1524)
				(type default)
			)
			(layer "F.SilkS")
		)
		(fp_line
			(start -0.7874 0.4064)
			(end -0.7874 -0.4064)
			(stroke
				(width 0.1524)
				(type default)
			)
			(layer "F.SilkS")
		)
		(fp_line
			(start 0.7874 -0.4064)
			(end 0.7874 0.4064)
			(stroke
				(width 0.1524)
				(type default)
			)
			(layer "F.SilkS")
		)
		(fp_line
			(start 0.7874 0.4064)
			(end -0.7874 0.4064)
			(stroke
				(width 0.1524)
				(type default)
			)
			(layer "F.SilkS")
		)
		(fp_line
			(start -0.67945 -0.305054)
			(end -0.12065 -0.305054)
			(stroke
				(width 0.1)
				(type default)
			)
			(layer "F.Fab")
		)
		(fp_line
			(start -0.67945 0.3048)
			(end -0.67945 -0.305054)
			(stroke
				(width 0.1)
				(type default)
			)
			(layer "F.Fab")
		)
		(fp_line
			(start -0.12065 -0.305054)
			(end -0.12065 -0.2794)
			(stroke
				(width 0.1)
				(type default)
			)
			(layer "F.Fab")
		)
		(fp_line
			(start -0.12065 -0.2794)
			(end 0.12065 -0.2794)
			(stroke
				(width 0.1)
				(type default)
			)
			(layer "F.Fab")
		)
		(fp_line
			(start -0.12065 0.2794)
			(end -0.12065 0.3048)
			(stroke
				(width 0.1)
				(type default)
			)
			(layer "F.Fab")
		)
		(fp_line
			(start -0.12065 0.3048)
			(end -0.67945 0.3048)
			(stroke
				(width 0.1)
				(type default)
			)
			(layer "F.Fab")
		)
		(fp_line
			(start 0.120396 0.2794)
			(end -0.12065 0.2794)
			(stroke
				(width 0.1)
				(type default)
			)
			(layer "F.Fab")
		)
		(fp_line
			(start 0.120396 0.3048)
			(end 0.120396 0.2794)
			(stroke
				(width 0.1)
				(type default)
			)
			(layer "F.Fab")
		)
		(fp_line
			(start 0.12065 -0.3048)
			(end 0.67945 -0.3048)
			(stroke
				(width 0.1)
				(type default)
			)
			(layer "F.Fab")
		)
		(fp_line
			(start 0.12065 -0.2794)
			(end 0.12065 -0.3048)
			(stroke
				(width 0.1)
				(type default)
			)
			(layer "F.Fab")
		)
		(fp_line
			(start 0.67945 -0.3048)
			(end 0.67945 0.3048)
			(stroke
				(width 0.1)
				(type default)
			)
			(layer "F.Fab")
		)
		(fp_line
			(start 0.67945 0.3048)
			(end 0.120396 0.3048)
			(stroke
				(width 0.1)
				(type default)
			)
			(layer "F.Fab")
		)
		(pad "1" smd rect
			(at -0.40005 0 180)
			(size 0.4572 0.508)
			(layers "F.Cu" "F.Mask" "F.Paste")
			(net "P5V_ADC")
		)
		(pad "2" smd rect
			(at 0.40005 0 180)
			(size 0.4572 0.508)
			(layers "F.Cu" "F.Mask" "F.Paste")
			(net "P5V_ADC_MAM")
		)
	)
	(footprint ""
		(layer "F.Cu")
		(at 118.718584 -56.582056 180)
		(property "Reference" "R6101"
			(at 0 0 180)
			(layer "F.SilkS")
			(hide yes)
			(effects
				(font
					(size 1.27 1.27)
				)
			)
		)
		(property "Value" ""
			(at 0 0 180)
			(layer "F.Fab")
			(effects
				(font
					(size 1.27 1.27)
				)
			)
		)
		(duplicate_pad_numbers_are_jumpers no)
		(fp_line
			(start 0.7874 0.4064)
			(end -0.7874 0.4064)
			(stroke
				(width 0.1524)
				(type default)
			)
			(layer "F.SilkS")
		)
		(fp_line
			(start 0.7874 -0.4064)
			(end 0.7874 0.4064)
			(stroke
				(width 0.1524)
				(type default)
			)
			(layer "F.SilkS")
		)
		(fp_line
			(start -0.7874 0.4064)
			(end -0.7874 -0.4064)
			(stroke
				(width 0.1524)
				(type default)
			)
			(layer "F.SilkS")
		)
		(fp_line
			(start -0.7874 -0.4064)
			(end 0.7874 -0.4064)
			(stroke
				(width 0.1524)
				(type default)
			)
			(layer "F.SilkS")
		)
		(fp_line
			(start 0.67945 0.3048)
			(end 0.120396 0.3048)
			(stroke
				(width 0.1)
				(type default)
			)
			(layer "F.Fab")
		)
		(fp_line
			(start 0.67945 -0.3048)
			(end 0.67945 0.3048)
			(stroke
				(width 0.1)
				(type default)
			)
			(layer "F.Fab")
		)
		(fp_line
			(start 0.12065 -0.2794)
			(end 0.12065 -0.3048)
			(stroke
				(width 0.1)
				(type default)
			)
			(layer "F.Fab")
		)
		(fp_line
			(start 0.12065 -0.3048)
			(end 0.67945 -0.3048)
			(stroke
				(width 0.1)
				(type default)
			)
			(layer "F.Fab")
		)
		(fp_line
			(start 0.120396 0.3048)
			(end 0.120396 0.2794)
			(stroke
				(width 0.1)
				(type default)
			)
			(layer "F.Fab")
		)
		(fp_line
			(start 0.120396 0.2794)
			(end -0.12065 0.2794)
			(stroke
				(width 0.1)
				(type default)
			)
			(layer "F.Fab")
		)
		(fp_line
			(start -0.12065 0.3048)
			(end -0.67945 0.3048)
			(stroke
				(width 0.1)
				(type default)
			)
			(layer "F.Fab")
		)
		(fp_line
			(start -0.12065 0.2794)
			(end -0.12065 0.3048)
			(stroke
				(width 0.1)
				(type default)
			)
			(layer "F.Fab")
		)
		(fp_line
			(start -0.12065 -0.2794)
			(end 0.12065 -0.2794)
			(stroke
				(width 0.1)
				(type default)
			)
			(layer "F.Fab")
		)
		(fp_line
			(start -0.12065 -0.305054)
			(end -0.12065 -0.2794)
			(stroke
				(width 0.1)
				(type default)
			)
			(layer "F.Fab")
		)
		(fp_line
			(start -0.67945 0.3048)
			(end -0.67945 -0.305054)
			(stroke
				(width 0.1)
				(type default)
			)
			(layer "F.Fab")
		)
		(fp_line
			(start -0.67945 -0.305054)
			(end -0.12065 -0.305054)
			(stroke
				(width 0.1)
				(type default)
			)
			(layer "F.Fab")
		)
		(pad "1" smd circle
			(at -0.40005 0 180)
			(size 0 0)
			(layers "F.Cu" "F.Mask" "F.Paste")
			(net "SCM_JTAG_MUX_S0")
		)
		(pad "2" smd circle
			(at 0.40005 0 180)
			(size 0 0)
			(layers "F.Cu" "F.Mask" "F.Paste")
			(net "SCM_JTAG_MUX_S0_R1")
		)
	)
)
